(kicad_pcb
	(version 20260206)
	(generator "pcbnew")
	(generator_version "10.0")
	(general
		(thickness 1.6)
		(legacy_teardrops no)
	)
	(paper "A4")
	(title_block
		(title "Wiwynn_Tioga_Pass_MB.brd")
		(comment 1 "Tioga Pass / footprint 1899 of 4770 (J4G2), pads 1-123 of 291")
	)
	(layers
		(0 "F.Cu" signal "TOP")
		(4 "In1.Cu" signal "L2GND")
		(6 "In2.Cu" signal "L3")
		(8 "In3.Cu" signal "L4GND")
		(10 "In4.Cu" signal "L5")
		(12 "In5.Cu" signal "L6GND")
		(14 "In6.Cu" signal "L7VCC")
		(16 "In7.Cu" signal "L8VCC")
		(18 "In8.Cu" signal "L9GND")
		(20 "In9.Cu" signal "L10")
		(22 "In10.Cu" signal "L11GND")
		(24 "In11.Cu" signal "L12")
		(26 "In12.Cu" signal "L13GND")
		(2 "B.Cu" signal "BOTTOM")
		(9 "F.Adhes" user "F.Adhesive")
		(11 "B.Adhes" user "B.Adhesive")
		(13 "F.Paste" user "Package Geometry/Pastemask Top")
		(15 "B.Paste" user "Package Geometry/Pastemask Bottom")
		(5 "F.SilkS" user "Ref Des/Silkscreen Top")
		(7 "B.SilkS" user "Ref Des/Silkscreen Bottom")
		(1 "F.Mask" user "Board Geometry/Soldermask Top")
		(3 "B.Mask" user "Board Geometry/Soldermask Bottom")
		(17 "Dwgs.User" user "User.Drawings")
		(19 "Cmts.User" user "User.Comments")
		(21 "Eco1.User" user "User.Eco1")
		(23 "Eco2.User" user "User.Eco2")
		(25 "Edge.Cuts" user "Board Geometry/Outline")
		(27 "Margin" user)
		(31 "F.CrtYd" user "Package Geometry/Place Bound Top")
		(29 "B.CrtYd" user "Package Geometry/Place Bound Bottom")
		(35 "F.Fab" user "Ref Des/Assembly Top")
		(33 "B.Fab" user "Ref Des/Assembly Bottom")
	)
	(footprint ""
		(layer "F.Cu")
		(at 194.700398 -5.822442 90)
		(property "Reference" "J4G2"
			(at 6.596888 37.58311 0)
			(unlocked yes)
			(layer "F.SilkS")
			(effects
				(font
					(size 0.7874 0.5842)
					(thickness 0.1524)
				)
				(justify left)
			)
		)
		(property "Value" ""
			(at 0 0 90)
			(layer "F.Fab")
			(effects
				(font
					(size 1.27 1.27)
				)
			)
		)
		(duplicate_pad_numbers_are_jumpers no)
		(pad "" thru_hole circle
			(at 2.29997 -5.649976 90)
			(size 2.8194 2.8194)
			(drill 2.4384)
			(layers "*.Cu" "*.Mask")
			(remove_unused_layers no)
			(clearance 0.127)
			(thermal_gap 0.127)
		)
		(pad "" thru_hole oval
			(at 2.29997 68.90004 90)
			(size 2.8194 1.5748)
			(drill oval 2.4384 1.1938)
			(layers "*.Cu" "*.Mask")
			(remove_unused_layers no)
			(clearance 0.127)
			(thermal_gap 0.127)
		)
		(pad "" thru_hole circle
			(at 2.29997 132.299964 90)
			(size 2.8194 2.8194)
			(drill 2.4384)
			(layers "*.Cu" "*.Mask")
			(remove_unused_layers no)
			(clearance 0.127)
			(thermal_gap 0.127)
		)
		(pad "1" smd rect
			(at 0 0 90)
			(size 1.8034 0.508)
			(layers "F.Cu" "F.Mask" "F.Paste")
			(net "P12V_NVDIMM_ABC")
		)
		(pad "2" smd rect
			(at 0 0.849884 90)
			(size 1.8034 0.508)
			(layers "F.Cu" "F.Mask" "F.Paste")
			(net "GND")
		)
		(pad "3" smd rect
			(at 0 1.700022 90)
			(size 1.8034 0.508)
			(layers "F.Cu" "F.Mask" "F.Paste")
			(net "M_B_DQ<5>")
		)
		(pad "4" smd rect
			(at 0 2.549906 90)
			(size 1.8034 0.508)
			(layers "F.Cu" "F.Mask" "F.Paste")
			(net "GND")
		)
		(pad "5" smd rect
			(at 0 3.400044 90)
			(size 1.8034 0.508)
			(layers "F.Cu" "F.Mask" "F.Paste")
			(net "M_B_DQ<1>")
		)
		(pad "6" smd rect
			(at 0 4.249928 90)
			(size 1.8034 0.508)
			(layers "F.Cu" "F.Mask" "F.Paste")
			(net "GND")
		)
		(pad "7" smd rect
			(at 0 5.100066 90)
			(size 1.8034 0.508)
			(layers "F.Cu" "F.Mask" "F.Paste")
			(net "M_B_DQS_DP<9>")
		)
		(pad "8" smd rect
			(at 0 5.94995 90)
			(size 1.8034 0.508)
			(layers "F.Cu" "F.Mask" "F.Paste")
			(net "M_B_DQS_DN<9>")
		)
		(pad "9" smd rect
			(at 0 6.800088 90)
			(size 1.8034 0.508)
			(layers "F.Cu" "F.Mask" "F.Paste")
			(net "GND")
		)
		(pad "10" smd rect
			(at 0 7.649972 90)
			(size 1.8034 0.508)
			(layers "F.Cu" "F.Mask" "F.Paste")
			(net "M_B_DQ<7>")
		)
		(pad "11" smd rect
			(at 0 8.50011 90)
			(size 1.8034 0.508)
			(layers "F.Cu" "F.Mask" "F.Paste")
			(net "GND")
		)
		(pad "12" smd rect
			(at 0 9.349994 90)
			(size 1.8034 0.508)
			(layers "F.Cu" "F.Mask" "F.Paste")
			(net "M_B_DQ<3>")
		)
		(pad "13" smd rect
			(at 0 10.199878 90)
			(size 1.8034 0.508)
			(layers "F.Cu" "F.Mask" "F.Paste")
			(net "GND")
		)
		(pad "14" smd rect
			(at 0 11.050016 90)
			(size 1.8034 0.508)
			(layers "F.Cu" "F.Mask" "F.Paste")
			(net "M_B_DQ<13>")
		)
		(pad "15" smd rect
			(at 0 11.8999 90)
			(size 1.8034 0.508)
			(layers "F.Cu" "F.Mask" "F.Paste")
			(net "GND")
		)
		(pad "16" smd rect
			(at 0 12.750038 90)
			(size 1.8034 0.508)
			(layers "F.Cu" "F.Mask" "F.Paste")
			(net "M_B_DQ<9>")
		)
		(pad "17" smd rect
			(at 0 13.599922 90)
			(size 1.8034 0.508)
			(layers "F.Cu" "F.Mask" "F.Paste")
			(net "GND")
		)
		(pad "18" smd rect
			(at 0 14.45006 90)
			(size 1.8034 0.508)
			(layers "F.Cu" "F.Mask" "F.Paste")
			(net "M_B_DQS_DP<10>")
		)
		(pad "19" smd rect
			(at 0 15.299944 90)
			(size 1.8034 0.508)
			(layers "F.Cu" "F.Mask" "F.Paste")
			(net "M_B_DQS_DN<10>")
		)
		(pad "20" smd rect
			(at 0 16.150082 90)
			(size 1.8034 0.508)
			(layers "F.Cu" "F.Mask" "F.Paste")
			(net "GND")
		)
		(pad "21" smd rect
			(at 0 16.999966 90)
			(size 1.8034 0.508)
			(layers "F.Cu" "F.Mask" "F.Paste")
			(net "M_B_DQ<15>")
		)
		(pad "22" smd rect
			(at 0 17.850104 90)
			(size 1.8034 0.508)
			(layers "F.Cu" "F.Mask" "F.Paste")
			(net "GND")
		)
		(pad "23" smd rect
			(at 0 18.699988 90)
			(size 1.8034 0.508)
			(layers "F.Cu" "F.Mask" "F.Paste")
			(net "M_B_DQ<11>")
		)
		(pad "24" smd rect
			(at 0 19.550126 90)
			(size 1.8034 0.508)
			(layers "F.Cu" "F.Mask" "F.Paste")
			(net "GND")
		)
		(pad "25" smd rect
			(at 0 20.40001 90)
			(size 1.8034 0.508)
			(layers "F.Cu" "F.Mask" "F.Paste")
			(net "M_B_DQ<21>")
		)
		(pad "26" smd rect
			(at 0 21.249894 90)
			(size 1.8034 0.508)
			(layers "F.Cu" "F.Mask" "F.Paste")
			(net "GND")
		)
		(pad "27" smd rect
			(at 0 22.100032 90)
			(size 1.8034 0.508)
			(layers "F.Cu" "F.Mask" "F.Paste")
			(net "M_B_DQ<17>")
		)
		(pad "28" smd rect
			(at 0 22.949916 90)
			(size 1.8034 0.508)
			(layers "F.Cu" "F.Mask" "F.Paste")
			(net "GND")
		)
		(pad "29" smd rect
			(at 0 23.800054 90)
			(size 1.8034 0.508)
			(layers "F.Cu" "F.Mask" "F.Paste")
			(net "M_B_DQS_DP<11>")
		)
		(pad "30" smd rect
			(at 0 24.649938 90)
			(size 1.8034 0.508)
			(layers "F.Cu" "F.Mask" "F.Paste")
			(net "M_B_DQS_DN<11>")
		)
		(pad "31" smd rect
			(at 0 25.500076 90)
			(size 1.8034 0.508)
			(layers "F.Cu" "F.Mask" "F.Paste")
			(net "GND")
		)
		(pad "32" smd rect
			(at 0 26.34996 90)
			(size 1.8034 0.508)
			(layers "F.Cu" "F.Mask" "F.Paste")
			(net "M_B_DQ<23>")
		)
		(pad "33" smd rect
			(at 0 27.200098 90)
			(size 1.8034 0.508)
			(layers "F.Cu" "F.Mask" "F.Paste")
			(net "GND")
		)
		(pad "34" smd rect
			(at 0 28.049982 90)
			(size 1.8034 0.508)
			(layers "F.Cu" "F.Mask" "F.Paste")
			(net "M_B_DQ<19>")
		)
		(pad "35" smd rect
			(at 0 28.90012 90)
			(size 1.8034 0.508)
			(layers "F.Cu" "F.Mask" "F.Paste")
			(net "GND")
		)
		(pad "36" smd rect
			(at 0 29.750004 90)
			(size 1.8034 0.508)
			(layers "F.Cu" "F.Mask" "F.Paste")
			(net "M_B_DQ<29>")
		)
		(pad "37" smd rect
			(at 0 30.599888 90)
			(size 1.8034 0.508)
			(layers "F.Cu" "F.Mask" "F.Paste")
			(net "GND")
		)
		(pad "38" smd rect
			(at 0 31.450026 90)
			(size 1.8034 0.508)
			(layers "F.Cu" "F.Mask" "F.Paste")
			(net "M_B_DQ<25>")
		)
		(pad "39" smd rect
			(at 0 32.29991 90)
			(size 1.8034 0.508)
			(layers "F.Cu" "F.Mask" "F.Paste")
			(net "GND")
		)
		(pad "40" smd rect
			(at 0 33.150048 90)
			(size 1.8034 0.508)
			(layers "F.Cu" "F.Mask" "F.Paste")
			(net "M_B_DQS_DP<12>")
		)
		(pad "41" smd rect
			(at 0 33.999932 90)
			(size 1.8034 0.508)
			(layers "F.Cu" "F.Mask" "F.Paste")
			(net "M_B_DQS_DN<12>")
		)
		(pad "42" smd rect
			(at 0 34.85007 90)
			(size 1.8034 0.508)
			(layers "F.Cu" "F.Mask" "F.Paste")
			(net "GND")
		)
		(pad "43" smd rect
			(at 0 35.699954 90)
			(size 1.8034 0.508)
			(layers "F.Cu" "F.Mask" "F.Paste")
			(net "M_B_DQ<31>")
		)
		(pad "44" smd rect
			(at 0 36.550092 90)
			(size 1.8034 0.508)
			(layers "F.Cu" "F.Mask" "F.Paste")
			(net "GND")
		)
		(pad "45" smd rect
			(at 0 37.399976 90)
			(size 1.8034 0.508)
			(layers "F.Cu" "F.Mask" "F.Paste")
			(net "M_B_DQ<27>")
		)
		(pad "46" smd rect
			(at 0 38.250114 90)
			(size 1.8034 0.508)
			(layers "F.Cu" "F.Mask" "F.Paste")
			(net "GND")
		)
		(pad "47" smd rect
			(at 0 39.099998 90)
			(size 1.8034 0.508)
			(layers "F.Cu" "F.Mask" "F.Paste")
			(net "M_B_ECC<5>")
		)
		(pad "48" smd rect
			(at 0 39.949882 90)
			(size 1.8034 0.508)
			(layers "F.Cu" "F.Mask" "F.Paste")
			(net "GND")
		)
		(pad "49" smd rect
			(at 0 40.80002 90)
			(size 1.8034 0.508)
			(layers "F.Cu" "F.Mask" "F.Paste")
			(net "M_B_ECC<1>")
		)
		(pad "50" smd rect
			(at 0 41.649904 90)
			(size 1.8034 0.508)
			(layers "F.Cu" "F.Mask" "F.Paste")
			(net "GND")
		)
		(pad "51" smd rect
			(at 0 42.500042 90)
			(size 1.8034 0.508)
			(layers "F.Cu" "F.Mask" "F.Paste")
			(net "M_B_DQS_DP<17>")
		)
		(pad "52" smd rect
			(at 0 43.349926 90)
			(size 1.8034 0.508)
			(layers "F.Cu" "F.Mask" "F.Paste")
			(net "M_B_DQS_DN<17>")
		)
		(pad "53" smd rect
			(at 0 44.200064 90)
			(size 1.8034 0.508)
			(layers "F.Cu" "F.Mask" "F.Paste")
			(net "GND")
		)
		(pad "54" smd rect
			(at 0 45.049948 90)
			(size 1.8034 0.508)
			(layers "F.Cu" "F.Mask" "F.Paste")
			(net "M_B_ECC<7>")
		)
		(pad "55" smd rect
			(at 0 45.900086 90)
			(size 1.8034 0.508)
			(layers "F.Cu" "F.Mask" "F.Paste")
			(net "GND")
		)
		(pad "56" smd rect
			(at 0 46.74997 90)
			(size 1.8034 0.508)
			(layers "F.Cu" "F.Mask" "F.Paste")
			(net "M_B_ECC<3>")
		)
		(pad "57" smd rect
			(at 0 47.600108 90)
			(size 1.8034 0.508)
			(layers "F.Cu" "F.Mask" "F.Paste")
			(net "GND")
		)
		(pad "58" smd rect
			(at 0 48.449992 90)
			(size 1.8034 0.508)
			(layers "F.Cu" "F.Mask" "F.Paste")
			(net "M_ABC_RST_N")
		)
		(pad "59" smd rect
			(at 0 49.299876 90)
			(size 1.8034 0.508)
			(layers "F.Cu" "F.Mask" "F.Paste")
			(net "PVDDQ_ABC")
		)
		(pad "60" smd rect
			(at 0 50.150014 90)
			(size 1.8034 0.508)
			(layers "F.Cu" "F.Mask" "F.Paste")
			(net "M_B_CKE<0>")
		)
		(pad "61" smd rect
			(at 0 50.999898 90)
			(size 1.8034 0.508)
			(layers "F.Cu" "F.Mask" "F.Paste")
			(net "PVDDQ_ABC")
		)
		(pad "62" smd rect
			(at 0 51.850036 90)
			(size 1.8034 0.508)
			(layers "F.Cu" "F.Mask" "F.Paste")
			(net "M_B_ACT_N")
		)
		(pad "63" smd rect
			(at 0 52.69992 90)
			(size 1.8034 0.508)
			(layers "F.Cu" "F.Mask" "F.Paste")
			(net "M_B_BG<0>")
		)
		(pad "64" smd rect
			(at 0 53.550058 90)
			(size 1.8034 0.508)
			(layers "F.Cu" "F.Mask" "F.Paste")
			(net "PVDDQ_ABC")
		)
		(pad "65" smd rect
			(at 0 54.399942 90)
			(size 1.8034 0.508)
			(layers "F.Cu" "F.Mask" "F.Paste")
			(net "M_B_MA<12>")
		)
		(pad "66" smd rect
			(at 0 55.25008 90)
			(size 1.8034 0.508)
			(layers "F.Cu" "F.Mask" "F.Paste")
			(net "M_B_MA<9>")
		)
		(pad "67" smd rect
			(at 0 56.099964 90)
			(size 1.8034 0.508)
			(layers "F.Cu" "F.Mask" "F.Paste")
			(net "PVDDQ_ABC")
		)
		(pad "68" smd rect
			(at 0 56.950102 90)
			(size 1.8034 0.508)
			(layers "F.Cu" "F.Mask" "F.Paste")
			(net "M_B_MA<8>")
		)
		(pad "69" smd rect
			(at 0 57.799986 90)
			(size 1.8034 0.508)
			(layers "F.Cu" "F.Mask" "F.Paste")
			(net "M_B_MA<6>")
		)
		(pad "70" smd rect
			(at 0 58.650124 90)
			(size 1.8034 0.508)
			(layers "F.Cu" "F.Mask" "F.Paste")
			(net "PVDDQ_ABC")
		)
		(pad "71" smd rect
			(at 0 59.500008 90)
			(size 1.8034 0.508)
			(layers "F.Cu" "F.Mask" "F.Paste")
			(net "M_B_MA<3>")
		)
		(pad "72" smd rect
			(at 0 60.349892 90)
			(size 1.8034 0.508)
			(layers "F.Cu" "F.Mask" "F.Paste")
			(net "M_B_MA<1>")
		)
		(pad "73" smd rect
			(at 0 61.20003 90)
			(size 1.8034 0.508)
			(layers "F.Cu" "F.Mask" "F.Paste")
			(net "PVDDQ_ABC")
		)
		(pad "74" smd rect
			(at 0 62.049914 90)
			(size 1.8034 0.508)
			(layers "F.Cu" "F.Mask" "F.Paste")
			(net "M_B_CLK_DP<0>")
		)
		(pad "75" smd rect
			(at 0 62.900052 90)
			(size 1.8034 0.508)
			(layers "F.Cu" "F.Mask" "F.Paste")
			(net "M_B_CLK_DN<0>")
		)
		(pad "76" smd rect
			(at 0 63.749936 90)
			(size 1.8034 0.508)
			(layers "F.Cu" "F.Mask" "F.Paste")
			(net "PVDDQ_ABC")
		)
		(pad "77" smd rect
			(at 0 64.600074 90)
			(size 1.8034 0.508)
			(layers "F.Cu" "F.Mask" "F.Paste")
			(net "PVTT_ABC")
		)
		(pad "78" smd rect
			(at 0 70.550024 90)
			(size 1.8034 0.508)
			(layers "F.Cu" "F.Mask" "F.Paste")
			(net "FM_DIMM_EVENT_COD_N")
		)
		(pad "79" smd rect
			(at 0 71.399908 90)
			(size 1.8034 0.508)
			(layers "F.Cu" "F.Mask" "F.Paste")
			(net "M_B_MA<0>")
		)
		(pad "80" smd rect
			(at 0 72.250046 90)
			(size 1.8034 0.508)
			(layers "F.Cu" "F.Mask" "F.Paste")
			(net "PVDDQ_ABC")
		)
		(pad "81" smd rect
			(at 0 73.09993 90)
			(size 1.8034 0.508)
			(layers "F.Cu" "F.Mask" "F.Paste")
			(net "M_B_BA<0>")
		)
		(pad "82" smd rect
			(at 0 73.950068 90)
			(size 1.8034 0.508)
			(layers "F.Cu" "F.Mask" "F.Paste")
			(net "M_B_MA<16>")
		)
		(pad "83" smd rect
			(at 0 74.799952 90)
			(size 1.8034 0.508)
			(layers "F.Cu" "F.Mask" "F.Paste")
			(net "PVDDQ_ABC")
		)
		(pad "84" smd rect
			(at 0 75.65009 90)
			(size 1.8034 0.508)
			(layers "F.Cu" "F.Mask" "F.Paste")
			(net "M_B_CS_N<0>")
		)
		(pad "85" smd rect
			(at 0 76.499974 90)
			(size 1.8034 0.508)
			(layers "F.Cu" "F.Mask" "F.Paste")
			(net "PVDDQ_ABC")
		)
		(pad "86" smd rect
			(at 0 77.350112 90)
			(size 1.8034 0.508)
			(layers "F.Cu" "F.Mask" "F.Paste")
			(net "M_B_MA<15>")
		)
		(pad "87" smd rect
			(at 0 78.199996 90)
			(size 1.8034 0.508)
			(layers "F.Cu" "F.Mask" "F.Paste")
			(net "M_B_ODT<0>")
		)
		(pad "88" smd rect
			(at 0 79.04988 90)
			(size 1.8034 0.508)
			(layers "F.Cu" "F.Mask" "F.Paste")
			(net "PVDDQ_ABC")
		)
		(pad "89" smd rect
			(at 0 79.900018 90)
			(size 1.8034 0.508)
			(layers "F.Cu" "F.Mask" "F.Paste")
			(net "M_B_CS_N<1>")
		)
		(pad "90" smd rect
			(at 0 80.749902 90)
			(size 1.8034 0.508)
			(layers "F.Cu" "F.Mask" "F.Paste")
			(net "PVDDQ_ABC")
		)
		(pad "91" smd rect
			(at 0 81.60004 90)
			(size 1.8034 0.508)
			(layers "F.Cu" "F.Mask" "F.Paste")
			(net "M_B_ODT<1>")
		)
		(pad "92" smd rect
			(at 0 82.449924 90)
			(size 1.8034 0.508)
			(layers "F.Cu" "F.Mask" "F.Paste")
			(net "PVDDQ_ABC")
		)
		(pad "93" smd rect
			(at 0 83.300062 90)
			(size 1.8034 0.508)
			(layers "F.Cu" "F.Mask" "F.Paste")
			(net "M_B_CS_N<2>")
		)
		(pad "94" smd rect
			(at 0 84.149946 90)
			(size 1.8034 0.508)
			(layers "F.Cu" "F.Mask" "F.Paste")
			(net "GND")
		)
		(pad "95" smd rect
			(at 0 85.000084 90)
			(size 1.8034 0.508)
			(layers "F.Cu" "F.Mask" "F.Paste")
			(net "M_B_DQ<37>")
		)
		(pad "96" smd rect
			(at 0 85.849968 90)
			(size 1.8034 0.508)
			(layers "F.Cu" "F.Mask" "F.Paste")
			(net "GND")
		)
		(pad "97" smd rect
			(at 0 86.700106 90)
			(size 1.8034 0.508)
			(layers "F.Cu" "F.Mask" "F.Paste")
			(net "M_B_DQ<33>")
		)
		(pad "98" smd rect
			(at 0 87.54999 90)
			(size 1.8034 0.508)
			(layers "F.Cu" "F.Mask" "F.Paste")
			(net "GND")
		)
		(pad "99" smd rect
			(at 0 88.399874 90)
			(size 1.8034 0.508)
			(layers "F.Cu" "F.Mask" "F.Paste")
			(net "M_B_DQS_DP<13>")
		)
		(pad "100" smd rect
			(at 0 89.250012 90)
			(size 1.8034 0.508)
			(layers "F.Cu" "F.Mask" "F.Paste")
			(net "M_B_DQS_DN<13>")
		)
		(pad "101" smd rect
			(at 0 90.099896 90)
			(size 1.8034 0.508)
			(layers "F.Cu" "F.Mask" "F.Paste")
			(net "GND")
		)
		(pad "102" smd rect
			(at 0 90.950034 90)
			(size 1.8034 0.508)
			(layers "F.Cu" "F.Mask" "F.Paste")
			(net "M_B_DQ<39>")
		)
		(pad "103" smd rect
			(at 0 91.799918 90)
			(size 1.8034 0.508)
			(layers "F.Cu" "F.Mask" "F.Paste")
			(net "GND")
		)
		(pad "104" smd rect
			(at 0 92.650056 90)
			(size 1.8034 0.508)
			(layers "F.Cu" "F.Mask" "F.Paste")
			(net "M_B_DQ<35>")
		)
		(pad "105" smd rect
			(at 0 93.49994 90)
			(size 1.8034 0.508)
			(layers "F.Cu" "F.Mask" "F.Paste")
			(net "GND")
		)
		(pad "106" smd rect
			(at 0 94.350078 90)
			(size 1.8034 0.508)
			(layers "F.Cu" "F.Mask" "F.Paste")
			(net "M_B_DQ<45>")
		)
		(pad "107" smd rect
			(at 0 95.199962 90)
			(size 1.8034 0.508)
			(layers "F.Cu" "F.Mask" "F.Paste")
			(net "GND")
		)
		(pad "108" smd rect
			(at 0 96.0501 90)
			(size 1.8034 0.508)
			(layers "F.Cu" "F.Mask" "F.Paste")
			(net "M_B_DQ<41>")
		)
		(pad "109" smd rect
			(at 0 96.899984 90)
			(size 1.8034 0.508)
			(layers "F.Cu" "F.Mask" "F.Paste")
			(net "GND")
		)
		(pad "110" smd rect
			(at 0 97.750122 90)
			(size 1.8034 0.508)
			(layers "F.Cu" "F.Mask" "F.Paste")
			(net "M_B_DQS_DP<14>")
		)
		(pad "111" smd rect
			(at 0 98.600006 90)
			(size 1.8034 0.508)
			(layers "F.Cu" "F.Mask" "F.Paste")
			(net "M_B_DQS_DN<14>")
		)
		(pad "112" smd rect
			(at 0 99.44989 90)
			(size 1.8034 0.508)
			(layers "F.Cu" "F.Mask" "F.Paste")
			(net "GND")
		)
		(pad "113" smd rect
			(at 0 100.300028 90)
			(size 1.8034 0.508)
			(layers "F.Cu" "F.Mask" "F.Paste")
			(net "M_B_DQ<47>")
		)
		(pad "114" smd rect
			(at 0 101.149912 90)
			(size 1.8034 0.508)
			(layers "F.Cu" "F.Mask" "F.Paste")
			(net "GND")
		)
		(pad "115" smd rect
			(at 0 102.00005 90)
			(size 1.8034 0.508)
			(layers "F.Cu" "F.Mask" "F.Paste")
			(net "M_B_DQ<43>")
		)
		(pad "116" smd rect
			(at 0 102.849934 90)
			(size 1.8034 0.508)
			(layers "F.Cu" "F.Mask" "F.Paste")
			(net "GND")
		)
		(pad "117" smd rect
			(at 0 103.700072 90)
			(size 1.8034 0.508)
			(layers "F.Cu" "F.Mask" "F.Paste")
			(net "M_B_DQ<53>")
		)
		(pad "118" smd rect
			(at 0 104.549956 90)
			(size 1.8034 0.508)
			(layers "F.Cu" "F.Mask" "F.Paste")
			(net "GND")
		)
		(pad "119" smd rect
			(at 0 105.400094 90)
			(size 1.8034 0.508)
			(layers "F.Cu" "F.Mask" "F.Paste")
			(net "M_B_DQ<49>")
		)
		(pad "120" smd rect
			(at 0 106.249978 90)
			(size 1.8034 0.508)
			(layers "F.Cu" "F.Mask" "F.Paste")
			(net "GND")
		)
	)
)
